# S9S_MB_2U (Grand Teton) — schematic parts with pin connectivity, parts 5884–5884 of 6093; source: Cadence DE-HDL packaged netlist (pstxprt.dat, pstxnet.dat, pstchip.dat)

U4  EMMITSBURG_REV0P9  GFNOCPU04302300-QV2N-MM#99A1WT IC  pkg BGA749_22X23  page 179  (pins 1-302 of 749)
  A4  RSVD_A4  TRI  = TP_PCH_RSVD<2>
  A6  VSS_A6  POWER  = GND
  A8  CLKOUT_SRC_N_13  OUT  = TP_CLK_100M_PCH_13_DN
  A10  CLKOUT_SRC_N_12  OUT  = TP_CLK_100M_PCH_12_DN
  A12  CLKOUT_SRC_N_5  OUT  = TP_CLK_100M_PCH_5_DN
  A14  CLKOUT_SRC_N_7  OUT  = TP_CLK_100M_PCH_7_DN
  A16  CLKOUT_SRC_N_0  OUT  = TP_CLK_100M_PCH_0_DN
  A18  CLKOUT_SRC_N_16  OUT  = TP_CLK_100M_PCH_16_DN
  A20  VSS_A20  POWER  = GND
  A22  VSS_A22  POWER  = GND
  A24  VSS_A24  POWER  = GND
  A26  VSS_A26  POWER  = GND
  A28  PMSYNC_CLK_P_1  OUT  = CLK_25M_PCH_CPU1_DP
  A30  DMI_0_RXN  IN  = DMI_CPU0_PCH_TX_C_DN<0>
  A32  DMI_2_RXN  IN  = DMI_CPU0_PCH_TX_C_DN<2>
  A34  DMI_4_SATA_19_PCIE3_19_RXN  IN  = DMI_CPU0_PCH_TX_C_DN<4>
  A36  DMI_6_SATA_17_PCIE3_17_RXN  IN  = DMI_CPU0_PCH_TX_C_DN<6>
  A38  VSS_A38  POWER  = GND
  A40  VSS_A40  POWER  = GND
  A41  VSS_A41  POWER  = FM_PCH_PRSNT_N
  AA1  GPP_D_21_GLB_RST_WARN_N  BI  = FM_PCH_GLB_RST_WARN_N
  AA3  GPP_D_22_USB2_OCB_7  BI  = FM_BIOS_DEBUG_EN_R_N
  AA5  VSS_AA5  POWER  = GND
  AA7  GPP_M_2  BI  = FAB_REV_ID2
  AA10  GPP_M_3  BI  = FM_BOARD_SKU_ID0
  AA13  GPP_M_1  BI  = FAB_REV_ID1
  AA17  VSS_AA17  POWER  = GND
  AA19  VSS_AA19  POWER  = GND
  AA20  VSS_AA20  POWER  = GND
  AA22  VSS_AA22  POWER  = GND
  AA24  VSS_AA24  POWER  = GND
  AA25  VSS_AA25  POWER  = GND
  AA27  VSS_AA27  POWER  = GND
  AA29  VCCP_1P05_FILTERED_AA29  POWER  = P1V05_PCH_PLL_AUX
  AA32  VSS_AA32  POWER  = GND
  AA36  VSS_AA36  POWER  = GND
  AA39  VSS_AA39  POWER  = GND
  AA41  SATA_4_PCIE3_4_USB3_4_RXN  IN  = P3E_PCH_E1S_RX_DN<0>
  AA43  SATA_4_PCIE3_4_USB3_4_RXP  IN  = P3E_PCH_E1S_RX_DP<0>
  AB2  GPP_D_10_BM_BUSY_N_SX_EXIT_HOLDOFF_N  BI  = IRQ_PCH_SCI_WHEA_N
  AB4  GPP_D_11_PLTRST_N  BI  = RST_PLTRST_N
  AB8  GPP_L_5  BI  = FM_PASSWORD_CLEAR_N
  AB11  GPP_M_7  BI  = FM_BOARD_SKU_ID4
  AB15  VSS_AB15  POWER  = GND
  AB17  VSS_AB17  POWER  = GND
  AB19  VCCP_1P05_AB19  POWER  = P1V05_PCH_AUX
  AB20  VCCP_1P05_AB20  POWER  = P1V05_PCH_AUX
  AB22  VCCP_1P05_AB22  POWER  = P1V05_PCH_AUX
  AB24  VCCP_1P05_AB24  POWER  = P1V05_PCH_AUX
  AB25  VSS_AB25  POWER  = GND
  AB27  VCCP_1P05_FILTERED_AB27  POWER  = P1V05_PCH_PLL_AUX
  AB31  VCCP_1P8_FILTERED_AB31  POWER  = P1V8_PCH_PLL_AUX
  AB34  VCCP_1P8_FILTERED_AB34  POWER  = P1V8_PCH_PLL_AUX
  AB37  VSS_AB37  POWER  = GND
  AB40  SATA_3_PCIE3_3_USB3_3_RXN  IN  = P3E_PCH_M2_RX_DN<3>
  AB42  SATA_3_PCIE3_3_USB3_3_RXP  IN  = P3E_PCH_M2_RX_DP<3>
  AC1  GPP_D_13_ADR_COMPLETE  BI  = FM_ADR_COMPLETE
  AC3  GPP_D_15_VRALERT_N  BI  = PU_PCH_VRALERT_N
  AC5  VSS_AC5  POWER  = GND
  AC7  GPP_L_7  BI  = TP_GPP_L_7
  AC10  GPP_L_2  BI  = TP_GPP_L_2
  AC13  GPIO_RCOMP_1P8_3P3  IN  = PD_RCOMP_1P8_3P3
  AC29  VSS_AC29  POWER  = GND
  AC32  VSS_AC32  POWER  = GND
  AC36  VSS_AC36  POWER  = GND
  AC39  VSS_AC39  POWER  = GND
  AC41  SATA_2_PCIE3_2_USB3_2_RXN  IN  = P3E_PCH_M2_RX_DN<2>
  AC43  SATA_2_PCIE3_2_USB3_2_RXP  IN  = P3E_PCH_M2_RX_DP<2>
  AD2  GPP_D_2_HS_SMBALERT_N_DMA_SMBALERT_N  BI  = TP_PCH_GPP_D_2
  AD4  GPP_D_16_ADR_ACK  BI  = FM_ADR_ACK
  AD8  VSS_AD8  POWER  = GND
  AD11  VSS_AD11  POWER  = GND
  AD15  VCCP_3P3_DSW_AD15  POWER  = P3V3_AUX
  AD17  VCCP_GPPI_1P8_3P3  POWER  = P3V3_AUX
  AD19  VSS_AD19  POWER  = GND
  AD20  VSS_AD20  POWER  = GND
  AD22  VSS_AD22  POWER  = GND
  AD24  VSS_AD24  POWER  = GND
  AD25  VCCP_1P05_AD25  POWER  = P1V05_PCH_AUX
  AD27  VCCP_1P05_AD27  POWER  = P1V05_PCH_AUX
  AD31  VSS_AD31  POWER  = GND
  AD34  VSS_AD34  POWER  = GND
  AD37  SATA_8_PCIE3_8_USB3_8_TXP  OUT  = P3E_PCH_BMC_TX_DP
  AD40  SATA_1_PCIE3_1_USB3_1_RXN  IN  = P3E_PCH_M2_RX_DN<1>
  AD42  SATA_1_PCIE3_1_USB3_1_RXP  IN  = P3E_PCH_M2_RX_DP<1>
  AE1  GPP_D_1_HS_SMBDATA_DMA_SMBDATA  BI  = SMB_HOST_BMC_3V3AUX_SDA
  AE3  GPP_D_8_CRASHLOG_TRIG_N  BI  = FM_PCH_CRASHLOG_TRIG_N
  AE5  VSS_AE5  POWER  = GND
  AE7  GPP_L_1_PM_DOWN_0  BI  = H_CPU0_PMDOWN_PCH
  AE10  GPP_L_8  BI  = TP_GPP_L_8
  AE13  VSS_AE13  POWER  = GND
  AE29  VCCP_1P05_FILTERED_AE29  POWER  = P1V05_PCH_PLL_AUX
  AE32  SATA_9_PCIE3_9_USB3_9_TXN  OUT  = USB3_PCH_TX_DN<4>
  AE36  SATA_8_PCIE3_8_USB3_8_TXN  OUT  = P3E_PCH_BMC_TX_DN
  AE39  VSS_AE39  POWER  = GND
  AE41  SATA_0_PCIE3_0_USB3_0_RXN  IN  = P3E_PCH_M2_RX_DN<0>
  AE43  SATA_0_PCIE3_0_USB3_0_RXP  IN  = P3E_PCH_M2_RX_DP<0>
  AF2  GPP_D_0_HS_SMBCLK_DMA_SMBCLK  BI  = SMB_HOST_BMC_3V3AUX_SCL
  AF4  GPP_D_18_MEMTRIP_N  BI  = FM_CPU_RMCA_CATERR_DLY_N
  AF8  GPP_L_0_PM_SYNC_0  BI  = H_CPU0_PMSYNC_PCH_R2
  AF11  GPP_L_3  BI  = FM_BIOS_ADV_FUNCTIONS
  AF15  RSVD_AF15  TRI  = TP_PCH_RSVD<16>
  AF17  VCCP_3P3_AF17  POWER  = P3V3_AUX
  AF19  VSS_AF19  POWER  = GND
  AF20  VCCP_VNN_AF20  POWER  = P1V05_PCH_AUX
  AF22  VCCP_VNN_AF22  POWER  = P1V05_PCH_AUX
  AF24  VSS_AF24  POWER  = GND
  AF25  VCCP_1P05_AF25  POWER  = P1V05_PCH_AUX
  AF27  VCCP_1P05_AF27  POWER  = P1V05_PCH_AUX
  AF31  VSS_AF31  POWER  = GND
  AF34  SATA_7_PCIE3_7_USB3_7_TXN  OUT  = P3E_PCH_E1S_TX_DN<3>
  AF37  SATA_6_PCIE3_6_USB3_6_TXN  OUT  = P3E_PCH_E1S_TX_DN<2>
  AF40  VSS_AF40  POWER  = GND
  AF42  VSS_AF42  POWER  = GND
  AG1  GPP_D_7  BI  = FM_ESPI_FLASH_MODE
  AG3  GPP_D_20_CATERR_N  BI  = TP_PCH_GPP_D_20
  AG5  VSS_AG5  POWER  = GND
  AG7  GPP_L_4  BI  = FM_ME_RCVR_N
  AG10  GPP_L_6  BI  = FM_MFG_MODE
  AG13  VSS_AG13  POWER  = GND
  AG17  VCCP_3P3_AG17  POWER  = P3V3_AUX
  AG19  VSS_AG19  POWER  = GND
  AG20  VCCP_VNN_AG20  POWER  = P1V05_PCH_AUX
  AG22  VCCP_VNN_AG22  POWER  = P1V05_PCH_AUX
  AG24  VSS_AG24  POWER  = GND
  AG25  VCCP_1P05_AG25  POWER  = P1V05_PCH_AUX
  AG27  VCCP_1P05_AG27  POWER  = P1V05_PCH_AUX
  AG29  VCCP_1P05_FILTERED_AG29  POWER  = P1V05_PCH_PLL_AUX
  AG32  SATA_9_PCIE3_9_USB3_9_TXP  OUT  = USB3_PCH_TX_DP<4>
  AG36  SATA_7_PCIE3_7_USB3_7_TXP  OUT  = P3E_PCH_E1S_TX_DP<3>
  AG39  VSS_AG39  POWER  = GND
  AG41  USB2P_13  BI  = TP_USB2_13_DP
  AG43  USB2N_13  BI  = TP_USB2_13_DN
  AH2  GPP_D_12_PCHHOT_N  BI  = FM_PCHHOT_N
  AH4  GPP_D_14_ADR_TRIGGER_N  BI  = FM_ADR_TRIGGER_R_N
  AH8  VSS_AH8  POWER  = GND
  AH11  WAKE_N  IN  = IRQ_LVC3_WAKE_N
  AH15  VCCRTC  POWER  = P3V3_RTC_AUX
  AH31  VSS_AH31  POWER  = GND
  AH34  SATA_5_PCIE3_5_USB3_5_TXN  OUT  = P3E_PCH_E1S_TX_DN<1>
  AH37  SATA_6_PCIE3_6_USB3_6_TXP  OUT  = P3E_PCH_E1S_TX_DP<2>
  AH40  USB2P_11  BI  = TP_USB2_11_DP
  AH42  USB2N_11  BI  = TP_USB2_11_DN
  AJ1  GPP_D_6  BI  = FM_FLASH_SECURITY_STRAP
  AJ3  GPP_D_9_PME_N  BI  = PU_LPC_PME_N
  AJ5  VSS_AJ5  POWER  = GND
  AJ7  LANPHYPC  OUT  = TP_PCH_GPP_O_11
  AJ10  SYS_RESET_N  IN  = RST_PCH_RSTBTN_R_N
  AJ13  SLP_S5_N  OUT  = TP_PCH_SLP_S5_N
  AJ17  VCCP_3P3_AJ17  POWER  = P3V3_AUX
  AJ19  VSS_AJ19  POWER  = GND
  AJ20  VCCP_VNN_AJ20  POWER  = P1V05_PCH_AUX
  AJ22  VCCP_VNN_AJ22  POWER  = P1V05_PCH_AUX
  AJ24  VSS_AJ24  POWER  = GND
  AJ25  VCCP_1P05_AJ25  POWER  = P1V05_PCH_AUX
  AJ27  VCCP_1P05_AJ27  POWER  = P1V05_PCH_AUX
  AJ29  VSS_AJ29  POWER  = GND
  AJ32  SATA_5_PCIE3_5_USB3_5_TXP  OUT  = P3E_PCH_E1S_TX_DP<1>
  AJ36  VSS_AJ36  POWER  = GND
  AJ39  VSS_AJ39  POWER  = GND
  AJ41  USB2P_9  BI  = TP_USB2_9_DP
  AJ43  USB2N_9  BI  = TP_USB2_9_DN
  AK2  VSS_AK2  POWER  = GND
  AK4  VSS_AK4  POWER  = GND
  AK8  SLP_LAN_N  OUT  = TP_SLP_LAN_N
  AK11  VSS_AK11  POWER  = GND
  AK15  VCCP_3P3_AK15  POWER  = P3V3_AUX
  AK31  SATA_0_PCIE3_0_USB3_0_TXP  OUT  = P3E_PCH_M2_TX_DP<0>
  AK34  SATA_3_PCIE3_3_USB3_3_TXN  OUT  = P3E_PCH_M2_TX_DN<3>
  AK37  VSS_AK37  POWER  = GND
  AK40  USB2P_7  BI  = USB2_7_DP
  AK42  USB2N_7  BI  = USB2_7_DN
  AL1  GPPC_C_19_MC_SMBCLK  BI  = PU_SMB_PCH_PLD_3V3AUX_SCL
  AL3  GPPC_C_17_ME_SML4ALERT_N  BI  = FM_BIOS_POST_CMPLT_N
  AL5  GPPC_C_18  BI  = FM_ADR_MODE1
  AL7  SLP_SUS_N  OUT  = FM_PCH_SLP_SUS_N
  AL10  SYS_PWROK  IN  = PWRGD_SYS_PWROK
  AL13  SLP_S4_N  OUT  = FM_PCH_SLP_S4_N
  AL17  VCCP_3P3_AL17  POWER  = P3V3_AUX
  AL19  VSS_AL19  POWER  = GND
  AL20  VCCP_VNN_AL20  POWER  = P1V05_PCH_AUX
  AL22  VCCP_VNN_AL22  POWER  = P1V05_PCH_AUX
  AL24  VSS_AL24  POWER  = GND
  AL25  VCCP_1P05_FILTERED_AL25  POWER  = P1V05_PCH_PLL_AUX
  AL27  VSS_AL27  POWER  = GND
  AL29  VSS_AL29  POWER  = GND
  AL32  SATA_0_PCIE3_0_USB3_0_TXN  OUT  = P3E_PCH_M2_TX_DN<0>
  AL36  SATA_4_PCIE3_4_USB3_4_TXN  OUT  = P3E_PCH_E1S_TX_DN<0>
  AL39  VSS_AL39  POWER  = GND
  AL41  USB2P_5  BI  = USB2_5_DP
  AL43  USB2N_5  BI  = USB2_5_DN
  AM8  VSS_AM8  POWER  = GND
  AM11  SLP_A_N  OUT  = TP_PCH_SLP_A_N
  AM15  VSS_AM15  POWER  = GND
  AM31  VSS_AM31  POWER  = GND
  AM34  SATA_3_PCIE3_3_USB3_3_TXP  OUT  = P3E_PCH_M2_TX_DP<3>
  AM37  SATA_4_PCIE3_4_USB3_4_TXP  OUT  = P3E_PCH_E1S_TX_DP<0>
  AN2  GPPC_C_21_MC_SMBALERT_N  BI  = PU_PCH_PLD_3V3AUX_ALERT_N
  AN4  GPPC_C_12_ME_SML3CLK  BI  = PU_SMB_SML3_3V3AUX_PCH_SCL
  AN7  ACPRESENT  IN  = PU_ACPRESENT
  AN10  GPP_O_0  BI  = FM_PCH_SPARE0
  AN13  VSS_AN13  POWER  = GND
  AN16  VSS_AN16  POWER  = GND
  AN20  VCCP_GPPE_1P8_3P3  POWER  = P3V3_AUX
  AN23  VCCP_VNN_AN23  POWER  = P1V05_PCH_AUX
  AN26  RSVD_AN26  TRI  = TP_PCH_RSVD<15>
  AN29  VSS_AN29  POWER  = GND
  AN32  VSS_AN32  POWER  = GND
  AN36  SATA_1_PCIE3_1_USB3_1_TXN  OUT  = P3E_PCH_M2_TX_DN<1>
  AN40  USB2P_3  BI  = USB2_3_DP
  AN42  USB2N_3  BI  = USB2_3_DN
  AP1  GPPC_C_6_ME_SML1CLK  BI  = SMB_SML1_PMBUS_3V3AUX_PCH_SCL_1
  AP3  GPPC_C_10_ME_SML2DATA  BI  = PD_PCH_GPPC_C10
  AP5  VSS_AP5  POWER  = GND
  AP8  SLP_S3_N  OUT  = FM_PCH_SLP_S3_N
  AP11  VSS_AP11  POWER  = GND
  AP15  GPPC_S_8_NMI_N  BI  = IRQ_PCH_CPU_NMI_EVENT_R_N
  AP18  VSS_AP18  POWER  = GND
  AP21  VCCP_VNN_AP21  POWER  = P1V05_PCH_AUX
  AP24  VSS_AP24  POWER  = GND
  AP28  VSS_AP28  POWER  = GND
  AP31  PHY_PCIE3_RCOMPN  BI  = PCH_PCIEUP_RCOMPN
  AP34  SATA_1_PCIE3_1_USB3_1_TXP  OUT  = P3E_PCH_M2_TX_DP<1>
  AP37  VSS_AP37  POWER  = GND
  AP39  VSS_AP39  POWER  = GND
  AP41  USB2P_1  BI  = TP_USB2_1_DP
  AP43  USB2N_1  BI  = TP_USB2_1_DN
  AR2  GPPC_C_9_ME_SML2CLK  BI  = PD_PCH_GPPC_C9
  AR4  GPPC_C_8_ME_SML1ALERT_N  BI  = IRQ_SML1_PMBUS_ALERT_N
  AR7  SUSCLK  OUT  = PD_SUSCLK
  AR10  PWRBTN_N  IN  = FM_BMC_PWRBTN_N
  AR13  GPPC_S_6_SUSWARN_N_SUSPWRDNACK  BI  = FM_EUP_LOT6_N
  AR16  GPPC_S_2_CPU_GP_0  BI  = FM_XTAL_INPUT_FREQUENCY_1_MGPIO
  AR20  VSS_AR20  POWER  = GND
  AR23  VCCP_VNN_AR23  POWER  = P1V05_PCH_AUX
  AR26  VCCP_1P05_AR26  POWER  = P1V05_PCH_AUX
  AR29  PHY_PCIE3_RCOMPP  BI  = PCH_PCIEUP_RCOMPP
  AR32  VSS_AR32  POWER  = GND
  AR36  SATA_2_PCIE3_2_USB3_2_TXN  OUT  = P3E_PCH_M2_TX_DN<2>
  AR40  USB2P_0  BI  = USB2_0_DP
  AR42  USB2N_0  BI  = USB2_0_DN
  AT1  GPPC_C_20_MC_SMBDATA  BI  = PU_SMB_PCH_PLD_3V3AUX_SDA
  AT3  GPPC_C_5_ME_SML0BALERT_N  BI  = PD_PCH_GPPC_C5
  AT5  VSS_AT5  POWER  = GND
  AT8  VSS_AT8  POWER  = GND
  AT11  VSS_AT11  POWER  = GND
  AT15  VSS_AT15  POWER  = GND
  AT18  GPPC_S_5_CPU_GP_3  BI  = FM_PCH_CONSENT_STRAP_N
  AT21  VSS_AT21  POWER  = GND
  AT24  VSS_AT24  POWER  = GND
  AT28  VSS_AT28  POWER  = GND
  AT31  VSS_AT31  POWER  = GND
  AT34  VSS_AT34  POWER  = GND
  AT37  SATA_2_PCIE3_2_USB3_2_TXP  OUT  = P3E_PCH_M2_TX_DP<2>
  AT39  VSS_AT39  POWER  = GND
  AT41  USB2P_2  BI  = TP_USB2_2_DP
  AT43  USB2N_2  BI  = TP_USB2_2_DN
  AU2  GPPC_C_2_ME_SML0ALERT_N  BI  = IRQ_SML0_ALERT_N
  AU4  GPPC_C_3_ME_SML0BDATA  BI  = SMB_SML0B_3V3AUX_SDA
  AU7  LAN_WAKE_N  IN  = PU_LAN_WAKE_N
  AU10  GPP_O_7  BI  = FM_PCH_SKIP_RTC_CLOCK
  AU13  GPPC_S_4_CPU_GP_2  BI  = FM_SPI_3V3_1V8_VOLTAGE
  AU16  GPPC_S_1_SPKR_TIME_SYNC_1  BI  = FM_PCH_SPKR
  AU20  VSS_AU20  POWER  = GND
  AU23  VSS_AU23  POWER  = GND
  AU26  VSS_AU26  POWER  = GND
  AU29  VSS_AU29  POWER  = GND
  AU32  VSS_AU32  POWER  = GND
  AU36  VSS_AU36  POWER  = GND
  AU40  USB2P_4  BI  = TP_USB2_4_DP
  AU42  USB2N_4  BI  = TP_USB2_4_DN
  AV1  GPPC_C_16_ME_SML4DATA  BI  = PU_SMB_SML4_3V3AUX_PCH_SDA
  AV3  GPPC_C_11_ME_SML2ALERT_N  BI  = FM_PMBUS_ALERT_B_EN
  AV5  VSS_AV5  POWER  = GND
  AV8  VSS_AV8  POWER  = GND
  AV11  GPPC_S_3_CPU_GP_1  BI  = FM_ADR_MODE0
  AV15  SPI0_IO_2  BI  = SPI_PCH_IO2
  AV18  GPPC_S_9_SMI_N  BI  = IRQ_SMI_ACTIVE_N
  AV21  RSVD_AV21  TRI  = NC_PCH_RSVD<4>
  AV24  GPP_E_4_SATA0_XPCIE_2  BI  = TP_EDSFF1A_TYPE_ID
  AV28  GPP_E_5_SATA0_XPCIE_3  BI  = TP_EDSFF1B_TYPE_ID
  AV31  GPP_E_10_SATA0_SDATAOUT_SATA0_GP  BI  = PD_PCH_GPP_E_10
  AV34  GPP_E_11_SATA1_SCLOCK_SATA1_LED_N  BI  = PD_PCH_GPP_E_11
  AV37  VSS_AV37  POWER  = GND
  AV39  VSS_AV39  POWER  = GND
  AV41  USB2P_6  BI  = TP_USB2_6_DP
  AV43  USB2N_6  BI  = TP_USB2_6_DN
  AW2  GPPC_C_14_ME_SML3ALERT_N  BI  = FM_THROTTLE_N
  AW4  GPPC_C_7_ME_SML1DATA  BI  = SMB_SML1_PMBUS_3V3AUX_PCH_SDA_1
  AW7  VSS_AW7  POWER  = GND
  AW10  GPPC_S_10  BI  = FM_JTAG_ODT_DISABLE
  AW13  SPI0_FLASH_0_CS_N  OUT  = SPI_PCH_CS0_R_N
  AW16  SPI0_MISO_IO_1  BI  = SPI_PCH_IO1
  AW20  GPP_E_15_SATA2_SLOAD_SATA2_GP  BI  = FM_ME_AUTHN_FAIL
  AW23  GPP_E_2_SATA1_XPCIE_2  BI  = TP_PCH_GPP_E_2
  AW26  RSVD_AW23  TRI  = NC_PCH_RSVD<3>
  AW29  GPP_E_16_SATA2_SDATAOUT_SATA2_DEVSLP  BI  = FM_ME_BT_DONE
  AW32  GPP_E_7_SATA0_USB3_XPCIE_1  BI  = FM_M2_SSD0_E7_PEDET
  AW36  GPP_E_8_SATA0_SCLOCK_SATA0_LED_N  BI  = PD_PCH_GPP_E_8
  AW40  USB2P_8  BI  = USB2_8_DP
  AW42  USB2N_8  BI  = USB2_8_DN
  AY1  GPPC_C_13_ME_SML3DATA  BI  = PU_SMB_SML3_3V3AUX_PCH_SDA
